(kicad_pcb
	(version 20241229)
	(generator "pcbnew")
	(generator_version "9.0")
	(general
		(thickness 1.6642)
		(legacy_teardrops no)
	)
	(paper "A3")
	(title_block
		(title "PolarFire SoM")
		(date "2025-07-22")
		(rev "1.1.4")
		(company "Antmicro Ltd")
		(comment 1 "www.antmicro.com")
		(comment 9 "footprints 145-148 of 470")
	)
	(layers
		(0 "F.Cu" mixed)
		(4 "In1.Cu" power)
		(6 "In2.Cu" signal)
		(8 "In3.Cu" power)
		(10 "In4.Cu" signal)
		(12 "In5.Cu" power)
		(14 "In6.Cu" power)
		(16 "In7.Cu" signal)
		(18 "In8.Cu" power)
		(20 "In9.Cu" signal)
		(22 "In10.Cu" power)
		(24 "In11.Cu" signal)
		(26 "In12.Cu" signal)
		(2 "B.Cu" mixed)
		(9 "F.Adhes" user "F.Adhesive")
		(11 "B.Adhes" user "B.Adhesive")
		(13 "F.Paste" user)
		(15 "B.Paste" user)
		(5 "F.SilkS" user "F.Silkscreen")
		(7 "B.SilkS" user "B.Silkscreen")
		(1 "F.Mask" user)
		(3 "B.Mask" user)
		(17 "Dwgs.User" user "User.Drawings")
		(19 "Cmts.User" user "User.Comments")
		(21 "Eco1.User" user "User.Eco1")
		(23 "Eco2.User" user "User.Eco2")
		(25 "Edge.Cuts" user)
		(27 "Margin" user)
		(31 "F.CrtYd" user "F.Courtyard")
		(29 "B.CrtYd" user "B.Courtyard")
		(35 "F.Fab" user)
		(33 "B.Fab" user)
	)
	(footprint "antmicro-footprints:R_0402_1005Metric"
		(layer "B.Cu")
		(at 219.911 116.704 180)
		(descr "Resistor SMD 0402")
		(tags "resistor SMD 0402")
		(property "Reference" "R67"
			(at -9.389 -4.546 0)
			(layer "B.SilkS")
			(effects
				(font
					(size 0.7 0.7)
					(thickness 0.15)
				)
				(justify left bottom mirror)
			)
		)
		(property "Value" "R_11k_0402"
			(at -1.011843 -1.772047 0)
			(layer "B.Fab")
			(hide yes)
			(effects
				(font
					(size 0.7 0.7)
					(thickness 0.15)
				)
				(justify left bottom mirror)
			)
		)
		(property "Datasheet" "https://www.bourns.com/docs/product-datasheets/cr.pdf"
			(at 0 0 180)
			(layer "F.Fab")
			(hide yes)
			(effects
				(font
					(size 1.27 1.27)
					(thickness 0.15)
				)
			)
		)
		(property "Description" "SMD Chip Resistor, 11 kohm, ± 1%, 62.5 mW, 0402 [1005 Metric], Thick Film, General Purpose"
			(at 0 0 180)
			(layer "F.Fab")
			(hide yes)
			(effects
				(font
					(size 1.27 1.27)
					(thickness 0.15)
				)
			)
		)
		(property "Author" "Antmicro"
			(at 439.822 233.408 0)
			(layer "B.Fab")
			(hide yes)
			(effects
				(font
					(size 1 1)
					(thickness 0.15)
				)
				(justify mirror)
			)
		)
		(property "License" "Apache-2.0"
			(at 439.822 233.408 0)
			(layer "B.Fab")
			(hide yes)
			(effects
				(font
					(size 1 1)
					(thickness 0.15)
				)
				(justify mirror)
			)
		)
		(property "MPN" "CR0402-FX-1102GLF"
			(at 439.822 233.408 0)
			(layer "B.Fab")
			(hide yes)
			(effects
				(font
					(size 1 1)
					(thickness 0.15)
				)
				(justify mirror)
			)
		)
		(property "Manufacturer" "Bourns"
			(at 439.822 233.408 0)
			(layer "B.Fab")
			(hide yes)
			(effects
				(font
					(size 1 1)
					(thickness 0.15)
				)
				(justify mirror)
			)
		)
		(property "Public" ""
			(at 439.822 233.408 0)
			(layer "B.Fab")
			(hide yes)
			(effects
				(font
					(size 1 1)
					(thickness 0.15)
				)
				(justify mirror)
			)
		)
		(property "Tolerance" "1%"
			(at 439.822 233.408 0)
			(layer "B.Fab")
			(hide yes)
			(effects
				(font
					(size 1 1)
					(thickness 0.15)
				)
				(justify mirror)
			)
		)
		(property "Val" "11k"
			(at 439.822 233.408 0)
			(layer "B.Fab")
			(hide yes)
			(effects
				(font
					(size 1 1)
					(thickness 0.15)
				)
				(justify mirror)
			)
		)
		(sheetname "/Ethernet/")
		(sheetfile "ethernet.kicad_sch")
		(attr smd)
		(fp_rect
			(start -0.925 0.47)
			(end 0.925 -0.47)
			(stroke
				(width 0.05)
				(type default)
			)
			(fill no)
			(layer "B.CrtYd")
		)
		(fp_rect
			(start -0.5 0.25)
			(end 0.5 -0.25)
			(stroke
				(width 0.15)
				(type solid)
			)
			(fill no)
			(layer "B.Fab")
		)
		(fp_text user "${REFERENCE}"
			(at -0.95 -3.168 0)
			(layer "B.Fab")
			(effects
				(font
					(size 0.7 0.7)
					(thickness 0.15)
				)
				(justify left bottom mirror)
			)
		)
		(fp_text user "Author: Antmicro"
			(at -0.95 -4.169 0)
			(layer "B.Fab")
			(effects
				(font
					(size 0.7 0.7)
					(thickness 0.15)
				)
				(justify left bottom mirror)
			)
		)
		(fp_text user "License: Apache-2.0"
			(at -0.95 -5.169 0)
			(layer "B.Fab")
			(effects
				(font
					(size 0.7 0.7)
					(thickness 0.15)
				)
				(justify left bottom mirror)
			)
		)
		(pad "1" smd roundrect
			(at -0.48 0 180)
			(size 0.59 0.64)
			(layers "B.Cu" "B.Mask" "B.Paste")
			(roundrect_rratio 0.25)
			(net 222 "Net-(U11-RBIAS)")
			(pintype "passive")
		)
		(pad "2" smd roundrect
			(at 0.48 0 180)
			(size 0.59 0.64)
			(layers "B.Cu" "B.Mask" "B.Paste")
			(roundrect_rratio 0.25)
			(net 417 "GND")
			(pintype "passive")
		)
	)
	(footprint "antmicro-footprints:R_0402_1005Metric"
		(layer "B.Cu")
		(at 218.361 123.254 90)
		(descr "Resistor SMD 0402")
		(tags "resistor SMD 0402")
		(property "Reference" "R141"
			(at -1.836 3.419 270)
			(layer "B.SilkS")
			(effects
				(font
					(size 0.7 0.7)
					(thickness 0.15)
				)
				(justify left bottom mirror)
			)
		)
		(property "Value" "R_2k2_0402"
			(at -1.011843 -1.772047 270)
			(layer "B.Fab")
			(hide yes)
			(effects
				(font
					(size 0.7 0.7)
					(thickness 0.15)
				)
				(justify left bottom mirror)
			)
		)
		(property "Datasheet" "https://www.bourns.com/docs/product-datasheets/cr.pdf"
			(at 0 0 90)
			(layer "F.Fab")
			(hide yes)
			(effects
				(font
					(size 1.27 1.27)
					(thickness 0.15)
				)
			)
		)
		(property "Description" "SMD Chip Resistor, 2.2 kohm, ± 1%, 62.5 mW, 0402 [1005 Metric], Thick Film, General Purpose"
			(at 0 0 90)
			(layer "F.Fab")
			(hide yes)
			(effects
				(font
					(size 1.27 1.27)
					(thickness 0.15)
				)
			)
		)
		(property "Author" "Antmicro"
			(at 341.615 -95.107 0)
			(layer "B.Fab")
			(hide yes)
			(effects
				(font
					(size 1 1)
					(thickness 0.15)
				)
				(justify mirror)
			)
		)
		(property "License" "Apache-2.0"
			(at 341.615 -95.107 0)
			(layer "B.Fab")
			(hide yes)
			(effects
				(font
					(size 1 1)
					(thickness 0.15)
				)
				(justify mirror)
			)
		)
		(property "MPN" "CR0402-FX-2201GLF"
			(at 341.615 -95.107 0)
			(layer "B.Fab")
			(hide yes)
			(effects
				(font
					(size 1 1)
					(thickness 0.15)
				)
				(justify mirror)
			)
		)
		(property "Manufacturer" "Bourns"
			(at 341.615 -95.107 0)
			(layer "B.Fab")
			(hide yes)
			(effects
				(font
					(size 1 1)
					(thickness 0.15)
				)
				(justify mirror)
			)
		)
		(property "Public" ""
			(at 341.615 -95.107 0)
			(layer "B.Fab")
			(hide yes)
			(effects
				(font
					(size 1 1)
					(thickness 0.15)
				)
				(justify mirror)
			)
		)
		(property "Tolerance" "1%"
			(at 341.615 -95.107 0)
			(layer "B.Fab")
			(hide yes)
			(effects
				(font
					(size 1 1)
					(thickness 0.15)
				)
				(justify mirror)
			)
		)
		(property "Val" "2k2"
			(at 341.615 -95.107 0)
			(layer "B.Fab")
			(hide yes)
			(effects
				(font
					(size 1 1)
					(thickness 0.15)
				)
				(justify mirror)
			)
		)
		(sheetname "/Ethernet/")
		(sheetfile "ethernet.kicad_sch")
		(attr smd)
		(fp_rect
			(start -0.925 0.47)
			(end 0.925 -0.47)
			(stroke
				(width 0.05)
				(type default)
			)
			(fill no)
			(layer "B.CrtYd")
		)
		(fp_rect
			(start -0.5 0.25)
			(end 0.5 -0.25)
			(stroke
				(width 0.15)
				(type solid)
			)
			(fill no)
			(layer "B.Fab")
		)
		(fp_text user "${REFERENCE}"
			(at -0.95 -3.168 270)
			(layer "B.Fab")
			(effects
				(font
					(size 0.7 0.7)
					(thickness 0.15)
				)
				(justify left bottom mirror)
			)
		)
		(fp_text user "License: Apache-2.0"
			(at -0.95 -5.169 270)
			(layer "B.Fab")
			(effects
				(font
					(size 0.7 0.7)
					(thickness 0.15)
				)
				(justify left bottom mirror)
			)
		)
		(fp_text user "Author: Antmicro"
			(at -0.95 -4.169 270)
			(layer "B.Fab")
			(effects
				(font
					(size 0.7 0.7)
					(thickness 0.15)
				)
				(justify left bottom mirror)
			)
		)
		(pad "1" smd roundrect
			(at -0.48 0 90)
			(size 0.59 0.64)
			(layers "B.Cu" "B.Mask" "B.Paste")
			(roundrect_rratio 0.25)
			(net 217 "ETH_PWDN_n")
			(pintype "passive")
		)
		(pad "2" smd roundrect
			(at 0.48 0 90)
			(size 0.59 0.64)
			(layers "B.Cu" "B.Mask" "B.Paste")
			(roundrect_rratio 0.25)
			(net 50 "+3V3")
			(pintype "passive")
		)
	)
	(footprint "antmicro-footprints:C_0402_1005Metric"
		(layer "B.Cu")
		(at 219.911 123.8)
		(descr "Capacitor SMD 0402")
		(tags "capacitor SMD 0402")
		(property "Reference" "C193"
			(at 6.539 3.76 0)
			(layer "B.SilkS")
			(effects
				(font
					(size 0.7 0.7)
					(thickness 0.15)
				)
				(justify right bottom mirror)
			)
		)
		(property "Value" "C_1u_0402"
			(at -1.022927 -2.155213 0)
			(layer "B.Fab")
			(hide yes)
			(effects
				(font
					(size 0.7 0.7)
					(thickness 0.15)
				)
				(justify right bottom mirror)
			)
		)
		(property "Datasheet" "https://product.tdk.com/en/search/capacitor/ceramic/mlcc/info?part_no=C1005X6S1A105K050BC"
			(at 0 0 0)
			(layer "F.Fab")
			(hide yes)
			(effects
				(font
					(size 1.27 1.27)
					(thickness 0.15)
				)
			)
		)
		(property "Description" "SMD Multilayer Ceramic Capacitor, 1 µF, 10 V, 0402 [1005 Metric], ± 10%, X6S, C"
			(at 0 0 0)
			(layer "F.Fab")
			(hide yes)
			(effects
				(font
					(size 1.27 1.27)
					(thickness 0.15)
				)
			)
		)
		(property "Author" "Antmicro"
			(at 0 0 0)
			(layer "B.Fab")
			(hide yes)
			(effects
				(font
					(size 1 1)
					(thickness 0.15)
				)
				(justify mirror)
			)
		)
		(property "Dielectric" ""
			(at 0 0 0)
			(layer "B.Fab")
			(hide yes)
			(effects
				(font
					(size 1 1)
					(thickness 0.15)
				)
				(justify mirror)
			)
		)
		(property "License" "Apache-2.0"
			(at 0 0 0)
			(layer "B.Fab")
			(hide yes)
			(effects
				(font
					(size 1 1)
					(thickness 0.15)
				)
				(justify mirror)
			)
		)
		(property "MPN" "C1005X6S1A105K050BC"
			(at 0 0 0)
			(layer "B.Fab")
			(hide yes)
			(effects
				(font
					(size 1 1)
					(thickness 0.15)
				)
				(justify mirror)
			)
		)
		(property "Manufacturer" "TDK"
			(at 0 0 0)
			(layer "B.Fab")
			(hide yes)
			(effects
				(font
					(size 1 1)
					(thickness 0.15)
				)
				(justify mirror)
			)
		)
		(property "Public" ""
			(at 0 0 0)
			(layer "B.Fab")
			(hide yes)
			(effects
				(font
					(size 1 1)
					(thickness 0.15)
				)
				(justify mirror)
			)
		)
		(property "Val" "1u"
			(at 0 0 0)
			(layer "B.Fab")
			(hide yes)
			(effects
				(font
					(size 1 1)
					(thickness 0.15)
				)
				(justify mirror)
			)
		)
		(property "Voltage" ""
			(at 0 0 0)
			(layer "B.Fab")
			(hide yes)
			(effects
				(font
					(size 1 1)
					(thickness 0.15)
				)
				(justify mirror)
			)
		)
		(sheetname "/Ethernet/")
		(sheetfile "ethernet.kicad_sch")
		(attr smd)
		(fp_rect
			(start -0.925 0.47)
			(end 0.925 -0.47)
			(stroke
				(width 0.05)
				(type default)
			)
			(fill no)
			(layer "B.CrtYd")
		)
		(fp_line
			(start -0.494 -0.248)
			(end -0.494 0.25)
			(stroke
				(width 0.15)
				(type solid)
			)
			(layer "B.Fab")
		)
		(fp_line
			(start -0.494 0.25)
			(end 0.504 0.25)
			(stroke
				(width 0.15)
				(type solid)
			)
			(layer "B.Fab")
		)
		(fp_line
			(start 0.504 -0.248)
			(end -0.494 -0.248)
			(stroke
				(width 0.15)
				(type solid)
			)
			(layer "B.Fab")
		)
		(fp_line
			(start 0.504 0.25)
			(end 0.504 -0.248)
			(stroke
				(width 0.15)
				(type solid)
			)
			(layer "B.Fab")
		)
		(fp_text user "${REFERENCE}"
			(at -0.939 -4.599 180)
			(layer "B.Fab")
			(effects
				(font
					(size 0.7 0.7)
					(thickness 0.15)
				)
				(justify left bottom mirror)
			)
		)
		(fp_text user "Author: Antmicro"
			(at -0.939 -3.399 180)
			(layer "B.Fab")
			(effects
				(font
					(size 0.7 0.7)
					(thickness 0.15)
				)
				(justify left bottom mirror)
			)
		)
		(fp_text user "License: Apache-2.0"
			(at -0.939 -5.799 180)
			(layer "B.Fab")
			(effects
				(font
					(size 0.7 0.7)
					(thickness 0.15)
				)
				(justify left bottom mirror)
			)
		)
		(pad "1" smd roundrect
			(at -0.48 0)
			(size 0.59 0.64)
			(layers "B.Cu" "B.Mask" "B.Paste")
			(roundrect_rratio 0.25)
			(net 417 "GND")
			(pintype "passive")
		)
		(pad "2" smd roundrect
			(at 0.48 0)
			(size 0.59 0.64)
			(layers "B.Cu" "B.Mask" "B.Paste")
			(roundrect_rratio 0.25)
			(net 418 "+2V5")
			(pintype "passive")
		)
	)
	(footprint "antmicro-footprints:C_0402_1005Metric"
		(layer "B.Cu")
		(at 194.72 137.64 90)
		(descr "Capacitor SMD 0402")
		(tags "capacitor SMD 0402")
		(property "Reference" "C41"
			(at -1.61 -0.52 90)
			(layer "B.SilkS")
			(effects
				(font
					(size 0.7 0.7)
					(thickness 0.15)
				)
				(justify right bottom mirror)
			)
		)
		(property "Value" "C_100n_0402"
			(at -1.022927 -2.155213 90)
			(layer "B.Fab")
			(hide yes)
			(effects
				(font
					(size 0.7 0.7)
					(thickness 0.15)
				)
				(justify right bottom mirror)
			)
		)
		(property "Datasheet" "https://www.murata.com/products/productdetail?partno=GRM155R61H104KE14%23"
			(at 0 0 90)
			(layer "F.Fab")
			(hide yes)
			(effects
				(font
					(size 1.27 1.27)
					(thickness 0.15)
				)
			)
		)
		(property "Description" "SMD Multilayer Ceramic Capacitor, 0.1 µF, 50 V, 0402 [1005 Metric], ± 10%, X5R, GRM Series"
			(at 0 0 90)
			(layer "F.Fab")
			(hide yes)
			(effects
				(font
					(size 1.27 1.27)
					(thickness 0.15)
				)
			)
		)
		(property "Author" "Antmicro"
			(at 332.36 -57.08 0)
			(layer "B.Fab")
			(hide yes)
			(effects
				(font
					(size 1 1)
					(thickness 0.15)
				)
				(justify mirror)
			)
		)
		(property "Dielectric" "X5R"
			(at 332.36 -57.08 0)
			(layer "B.Fab")
			(hide yes)
			(effects
				(font
					(size 1 1)
					(thickness 0.15)
				)
				(justify mirror)
			)
		)
		(property "License" "Apache-2.0"
			(at 332.36 -57.08 0)
			(layer "B.Fab")
			(hide yes)
			(effects
				(font
					(size 1 1)
					(thickness 0.15)
				)
				(justify mirror)
			)
		)
		(property "MPN" "GRM155R61H104KE14D"
			(at 332.36 -57.08 0)
			(layer "B.Fab")
			(hide yes)
			(effects
				(font
					(size 1 1)
					(thickness 0.15)
				)
				(justify mirror)
			)
		)
		(property "Manufacturer" "Murata"
			(at 332.36 -57.08 0)
			(layer "B.Fab")
			(hide yes)
			(effects
				(font
					(size 1 1)
					(thickness 0.15)
				)
				(justify mirror)
			)
		)
		(property "Public" ""
			(at 332.36 -57.08 0)
			(layer "B.Fab")
			(hide yes)
			(effects
				(font
					(size 1 1)
					(thickness 0.15)
				)
				(justify mirror)
			)
		)
		(property "Val" "100n"
			(at 332.36 -57.08 0)
			(layer "B.Fab")
			(hide yes)
			(effects
				(font
					(size 1 1)
					(thickness 0.15)
				)
				(justify mirror)
			)
		)
		(property "Voltage" "50V"
			(at 332.36 -57.08 0)
			(layer "B.Fab")
			(hide yes)
			(effects
				(font
					(size 1 1)
					(thickness 0.15)
				)
				(justify mirror)
			)
		)
		(sheetname "/FPGA Supply/")
		(sheetfile "fpga-supply.kicad_sch")
		(attr smd)
		(fp_rect
			(start -0.925 0.47)
			(end 0.925 -0.47)
			(stroke
				(width 0.05)
				(type default)
			)
			(fill no)
			(layer "B.CrtYd")
		)
		(fp_line
			(start 0.504 -0.248)
			(end -0.494 -0.248)
			(stroke
				(width 0.15)
				(type solid)
			)
			(layer "B.Fab")
		)
		(fp_line
			(start -0.494 -0.248)
			(end -0.494 0.25)
			(stroke
				(width 0.15)
				(type solid)
			)
			(layer "B.Fab")
		)
		(fp_line
			(start 0.504 0.25)
			(end 0.504 -0.248)
			(stroke
				(width 0.15)
				(type solid)
			)
			(layer "B.Fab")
		)
		(fp_line
			(start -0.494 0.25)
			(end 0.504 0.25)
			(stroke
				(width 0.15)
				(type solid)
			)
			(layer "B.Fab")
		)
		(fp_text user "Author: Antmicro"
			(at -0.939 -3.399 270)
			(layer "B.Fab")
			(effects
				(font
					(size 0.7 0.7)
					(thickness 0.15)
				)
				(justify left bottom mirror)
			)
		)
		(fp_text user "License: Apache-2.0"
			(at -0.939 -5.799 270)
			(layer "B.Fab")
			(effects
				(font
					(size 0.7 0.7)
					(thickness 0.15)
				)
				(justify left bottom mirror)
			)
		)
		(fp_text user "${REFERENCE}"
			(at -0.939 -4.599 270)
			(layer "B.Fab")
			(effects
				(font
					(size 0.7 0.7)
					(thickness 0.15)
				)
				(justify left bottom mirror)
			)
		)
		(pad "1" smd roundrect
			(at -0.48 0 90)
			(size 0.59 0.64)
			(layers "B.Cu" "B.Mask" "B.Paste")
			(roundrect_rratio 0.25)
			(net 417 "GND")
			(pintype "passive")
		)
		(pad "2" smd roundrect
			(at 0.48 0 90)
			(size 0.59 0.64)
			(layers "B.Cu" "B.Mask" "B.Paste")
			(roundrect_rratio 0.25)
			(net 418 "+2V5")
			(pintype "passive")
		)
	)
)
